# T6G (Grand Teton) — schematic netlist excerpt (pin names and nets, part order shuffled) for the footprints in the layout excerpt that follows; sources: Cadence DE-HDL packaged netlist, KiCad conversion of 04192023_DAF0TMB3IC0_F0TG_MB_C_brd_V02_OCP.brd

R173  Q_RES  33 5% CHIP  pkg 0402LF  page 81 : A = FM_PLD_CPU1_PRSNT_HDT ; B = CPU1_HDT_BYPASS_SEL
R1004  Q_RES  0 5% CHIP  pkg 0201LF  page 287 : A = RST_RT_CPU0_P1_PERST_N ; B = RST_RT_CPU0_P1_PERST_R_N
R9010  Q_RES  0 5% CHIP  pkg 0402LF  page 245 : A = PRSNT_CABLE_SWB_B1_ISO_N ; B = PRSNT_CABLE_SWB_B1_ISO_R_N

(kicad_pcb
	(version 20260206)
	(generator "pcbnew")
	(generator_version "10.0")
	(general
		(thickness 1.6)
		(legacy_teardrops no)
	)
	(paper "A4")
	(title_block
		(title "04192023_DAF0TMB3IC0_F0TG_MB_C_brd_V02_OCP.brd")
		(comment 1 "Grand Teton / footprints 2718-2720 of 8354")
	)
	(layers
		(0 "F.Cu" signal "TOP")
		(4 "In1.Cu" signal "GND")
		(6 "In2.Cu" signal "IN1")
		(8 "In3.Cu" signal "GND1")
		(10 "In4.Cu" signal "IN2")
		(12 "In5.Cu" signal "GND2")
		(14 "In6.Cu" signal "IN3")
		(16 "In7.Cu" signal "GND3")
		(18 "In8.Cu" signal "VCC")
		(20 "In9.Cu" signal "VCC1")
		(22 "In10.Cu" signal "GND4")
		(24 "In11.Cu" signal "IN4")
		(26 "In12.Cu" signal "GND5")
		(28 "In13.Cu" signal "IN5")
		(30 "In14.Cu" signal "GND6")
		(32 "In15.Cu" signal "IN6")
		(34 "In16.Cu" signal "GND7")
		(2 "B.Cu" signal "BOTTOM")
		(9 "F.Adhes" user "F.Adhesive")
		(11 "B.Adhes" user "B.Adhesive")
		(13 "F.Paste" user "Package Geometry/Pastemask Top")
		(15 "B.Paste" user "Package Geometry/Pastemask Bottom")
		(5 "F.SilkS" user "Ref Des/Silkscreen Top")
		(7 "B.SilkS" user "Ref Des/Silkscreen Bottom")
		(1 "F.Mask" user "Board Geometry/Soldermask Top")
		(3 "B.Mask" user "Board Geometry/Soldermask Bottom")
		(17 "Dwgs.User" user "User.Drawings")
		(19 "Cmts.User" user "User.Comments")
		(21 "Eco1.User" user "User.Eco1")
		(23 "Eco2.User" user "User.Eco2")
		(25 "Edge.Cuts" user "Board Geometry/Outline")
		(27 "Margin" user)
		(31 "F.CrtYd" user "Package Geometry/Place Bound Top")
		(29 "B.CrtYd" user "Package Geometry/Place Bound Bottom")
		(35 "F.Fab" user "Ref Des/Assembly Top")
		(33 "B.Fab" user "Ref Des/Assembly Bottom")
	)
	(footprint ""
		(layer "F.Cu")
		(at 192.151 -133.568948 90)
		(property "Reference" "R173"
			(at 0 0 90)
			(layer "F.SilkS")
			(hide yes)
			(effects
				(font
					(size 1.27 1.27)
				)
			)
		)
		(property "Value" ""
			(at 0 0 90)
			(layer "F.Fab")
			(effects
				(font
					(size 1.27 1.27)
				)
			)
		)
		(duplicate_pad_numbers_are_jumpers no)
		(fp_line
			(start 0.7874 -0.4064)
			(end 0.7874 0.4064)
			(stroke
				(width 0.1524)
				(type default)
			)
			(layer "F.SilkS")
		)
		(fp_line
			(start -0.7874 -0.4064)
			(end 0.7874 -0.4064)
			(stroke
				(width 0.1524)
				(type default)
			)
			(layer "F.SilkS")
		)
		(fp_line
			(start 0.7874 0.4064)
			(end -0.7874 0.4064)
			(stroke
				(width 0.1524)
				(type default)
			)
			(layer "F.SilkS")
		)
		(fp_line
			(start -0.7874 0.4064)
			(end -0.7874 -0.4064)
			(stroke
				(width 0.1524)
				(type default)
			)
			(layer "F.SilkS")
		)
		(fp_line
			(start -0.12065 -0.305054)
			(end -0.12065 -0.2794)
			(stroke
				(width 0.1)
				(type default)
			)
			(layer "F.Fab")
		)
		(fp_line
			(start -0.67945 -0.305054)
			(end -0.12065 -0.305054)
			(stroke
				(width 0.1)
				(type default)
			)
			(layer "F.Fab")
		)
		(fp_line
			(start 0.67945 -0.3048)
			(end 0.67945 0.3048)
			(stroke
				(width 0.1)
				(type default)
			)
			(layer "F.Fab")
		)
		(fp_line
			(start 0.12065 -0.3048)
			(end 0.67945 -0.3048)
			(stroke
				(width 0.1)
				(type default)
			)
			(layer "F.Fab")
		)
		(fp_line
			(start 0.12065 -0.2794)
			(end 0.12065 -0.3048)
			(stroke
				(width 0.1)
				(type default)
			)
			(layer "F.Fab")
		)
		(fp_line
			(start -0.12065 -0.2794)
			(end 0.12065 -0.2794)
			(stroke
				(width 0.1)
				(type default)
			)
			(layer "F.Fab")
		)
		(fp_line
			(start 0.120396 0.2794)
			(end -0.12065 0.2794)
			(stroke
				(width 0.1)
				(type default)
			)
			(layer "F.Fab")
		)
		(fp_line
			(start -0.12065 0.2794)
			(end -0.12065 0.3048)
			(stroke
				(width 0.1)
				(type default)
			)
			(layer "F.Fab")
		)
		(fp_line
			(start 0.67945 0.3048)
			(end 0.120396 0.3048)
			(stroke
				(width 0.1)
				(type default)
			)
			(layer "F.Fab")
		)
		(fp_line
			(start 0.120396 0.3048)
			(end 0.120396 0.2794)
			(stroke
				(width 0.1)
				(type default)
			)
			(layer "F.Fab")
		)
		(fp_line
			(start -0.12065 0.3048)
			(end -0.67945 0.3048)
			(stroke
				(width 0.1)
				(type default)
			)
			(layer "F.Fab")
		)
		(fp_line
			(start -0.67945 0.3048)
			(end -0.67945 -0.305054)
			(stroke
				(width 0.1)
				(type default)
			)
			(layer "F.Fab")
		)
		(pad "1" smd circle
			(at -0.40005 0 90)
			(size 0 0)
			(layers "F.Cu" "F.Mask" "F.Paste")
			(net "FM_PLD_CPU1_PRSNT_HDT")
		)
		(pad "2" smd circle
			(at 0.40005 0 90)
			(size 0 0)
			(layers "F.Cu" "F.Mask" "F.Paste")
			(net "CPU1_HDT_BYPASS_SEL")
		)
	)
	(footprint ""
		(layer "F.Cu")
		(at 189.327028 -428.94758 -90)
		(property "Reference" "R9010"
			(at 0 0 270)
			(layer "F.SilkS")
			(hide yes)
			(effects
				(font
					(size 1.27 1.27)
				)
			)
		)
		(property "Value" ""
			(at 0 0 270)
			(layer "F.Fab")
			(effects
				(font
					(size 1.27 1.27)
				)
			)
		)
		(duplicate_pad_numbers_are_jumpers no)
		(fp_line
			(start -0.7874 0.4064)
			(end -0.7874 -0.4064)
			(stroke
				(width 0.1524)
				(type default)
			)
			(layer "F.SilkS")
		)
		(fp_line
			(start 0.7874 0.4064)
			(end -0.7874 0.4064)
			(stroke
				(width 0.1524)
				(type default)
			)
			(layer "F.SilkS")
		)
		(fp_line
			(start -0.7874 -0.4064)
			(end 0.7874 -0.4064)
			(stroke
				(width 0.1524)
				(type default)
			)
			(layer "F.SilkS")
		)
		(fp_line
			(start 0.7874 -0.4064)
			(end 0.7874 0.4064)
			(stroke
				(width 0.1524)
				(type default)
			)
			(layer "F.SilkS")
		)
		(fp_line
			(start -0.67945 0.3048)
			(end -0.67945 -0.305054)
			(stroke
				(width 0.1)
				(type default)
			)
			(layer "F.Fab")
		)
		(fp_line
			(start -0.12065 0.3048)
			(end -0.67945 0.3048)
			(stroke
				(width 0.1)
				(type default)
			)
			(layer "F.Fab")
		)
		(fp_line
			(start 0.120396 0.3048)
			(end 0.120396 0.2794)
			(stroke
				(width 0.1)
				(type default)
			)
			(layer "F.Fab")
		)
		(fp_line
			(start 0.67945 0.3048)
			(end 0.120396 0.3048)
			(stroke
				(width 0.1)
				(type default)
			)
			(layer "F.Fab")
		)
		(fp_line
			(start -0.12065 0.2794)
			(end -0.12065 0.3048)
			(stroke
				(width 0.1)
				(type default)
			)
			(layer "F.Fab")
		)
		(fp_line
			(start 0.120396 0.2794)
			(end -0.12065 0.2794)
			(stroke
				(width 0.1)
				(type default)
			)
			(layer "F.Fab")
		)
		(fp_line
			(start -0.12065 -0.2794)
			(end 0.12065 -0.2794)
			(stroke
				(width 0.1)
				(type default)
			)
			(layer "F.Fab")
		)
		(fp_line
			(start 0.12065 -0.2794)
			(end 0.12065 -0.3048)
			(stroke
				(width 0.1)
				(type default)
			)
			(layer "F.Fab")
		)
		(fp_line
			(start 0.12065 -0.3048)
			(end 0.67945 -0.3048)
			(stroke
				(width 0.1)
				(type default)
			)
			(layer "F.Fab")
		)
		(fp_line
			(start 0.67945 -0.3048)
			(end 0.67945 0.3048)
			(stroke
				(width 0.1)
				(type default)
			)
			(layer "F.Fab")
		)
		(fp_line
			(start -0.67945 -0.305054)
			(end -0.12065 -0.305054)
			(stroke
				(width 0.1)
				(type default)
			)
			(layer "F.Fab")
		)
		(fp_line
			(start -0.12065 -0.305054)
			(end -0.12065 -0.2794)
			(stroke
				(width 0.1)
				(type default)
			)
			(layer "F.Fab")
		)
		(pad "1" smd circle
			(at -0.40005 0 270)
			(size 0 0)
			(layers "F.Cu" "F.Mask" "F.Paste")
			(net "PRSNT_CABLE_SWB_B1_ISO_N")
		)
		(pad "2" smd circle
			(at 0.40005 0 270)
			(size 0 0)
			(layers "F.Cu" "F.Mask" "F.Paste")
			(net "PRSNT_CABLE_SWB_B1_ISO_R_N")
		)
	)
	(footprint ""
		(layer "F.Cu")
		(at 356.69601 -404.0124 -90)
		(property "Reference" "R1004"
			(at 0 0 270)
			(layer "F.SilkS")
			(hide yes)
			(effects
				(font
					(size 1.27 1.27)
				)
			)
		)
		(property "Value" ""
			(at 0 0 270)
			(layer "F.Fab")
			(effects
				(font
					(size 1.27 1.27)
				)
			)
		)
		(duplicate_pad_numbers_are_jumpers no)
		(fp_line
			(start -0.32512 0.175006)
			(end -0.32512 -0.175006)
			(stroke
				(width 0.1)
				(type default)
			)
			(layer "F.Fab")
		)
		(fp_line
			(start 0.32512 0.175006)
			(end -0.32512 0.175006)
			(stroke
				(width 0.1)
				(type default)
			)
			(layer "F.Fab")
		)
		(fp_line
			(start -0.32512 -0.175006)
			(end 0.32512 -0.175006)
			(stroke
				(width 0.1)
				(type default)
			)
			(layer "F.Fab")
		)
		(fp_line
			(start 0.32512 -0.175006)
			(end 0.32512 0.175006)
			(stroke
				(width 0.1)
				(type default)
			)
			(layer "F.Fab")
		)
		(pad "1" smd rect
			(at -0.2667 0 270)
			(size 0.3048 0.381)
			(layers "F.Cu" "F.Mask" "F.Paste")
			(net "RST_RT_CPU0_P1_PERST_N")
		)
		(pad "2" smd rect
			(at 0.2667 0 90)
			(size 0.3048 0.381)
			(layers "F.Cu" "F.Mask" "F.Paste")
			(net "RST_RT_CPU0_P1_PERST_R_N")
		)
	)
)
